# S9S_MB_2U (Grand Teton) — schematic netlist excerpt (pin names and nets, part order shuffled) for the footprints in the layout excerpt that follows; sources: Cadence DE-HDL packaged netlist, KiCad conversion of 03242023_DA0F0TMBIJ0_F0T_Motherboard_J_brd_V01_OCP.brd

R3178  Q_RES  0 5% CHIP  pkg 0402LF  page 159 : A = USB2_5_R1_DP ; B = USB2_5_DP
C2459  Q_CAP  1000PF 50V 10% EMPTY  pkg 0603  page 305 : A = P12V_HSC_TEMP_D+ ; B = P12V_HSC_TEMP_D-

(kicad_pcb
	(version 20260206)
	(generator "pcbnew")
	(generator_version "10.0")
	(general
		(thickness 1.6)
		(legacy_teardrops no)
	)
	(paper "A4")
	(title_block
		(title "03242023_DA0F0TMBIJ0_F0T_Motherboard_J_brd_V01_OCP.brd")
		(comment 1 "Grand Teton / footprints 2620-2621 of 6105")
	)
	(layers
		(0 "F.Cu" signal "TOP")
		(4 "In1.Cu" signal "GND")
		(6 "In2.Cu" signal "IN1")
		(8 "In3.Cu" signal "GND1")
		(10 "In4.Cu" signal "IN2")
		(12 "In5.Cu" signal "GND2")
		(14 "In6.Cu" signal "IN3")
		(16 "In7.Cu" signal "GND3")
		(18 "In8.Cu" signal "VCC")
		(20 "In9.Cu" signal "VCC1")
		(22 "In10.Cu" signal "GND4")
		(24 "In11.Cu" signal "IN4")
		(26 "In12.Cu" signal "GND5")
		(28 "In13.Cu" signal "IN5")
		(30 "In14.Cu" signal "GND6")
		(32 "In15.Cu" signal "IN6")
		(34 "In16.Cu" signal "GND7")
		(2 "B.Cu" signal "BOTTOM")
		(9 "F.Adhes" user "F.Adhesive")
		(11 "B.Adhes" user "B.Adhesive")
		(13 "F.Paste" user "Package Geometry/Pastemask Top")
		(15 "B.Paste" user "Package Geometry/Pastemask Bottom")
		(5 "F.SilkS" user "Ref Des/Silkscreen Top")
		(7 "B.SilkS" user "Ref Des/Silkscreen Bottom")
		(1 "F.Mask" user "Board Geometry/Soldermask Top")
		(3 "B.Mask" user "Board Geometry/Soldermask Bottom")
		(17 "Dwgs.User" user "User.Drawings")
		(19 "Cmts.User" user "User.Comments")
		(21 "Eco1.User" user "User.Eco1")
		(23 "Eco2.User" user "User.Eco2")
		(25 "Edge.Cuts" user "Board Geometry/Outline")
		(27 "Margin" user)
		(31 "F.CrtYd" user "Package Geometry/Place Bound Top")
		(29 "B.CrtYd" user "Package Geometry/Place Bound Bottom")
		(35 "F.Fab" user "Ref Des/Assembly Top")
		(33 "B.Fab" user "Ref Des/Assembly Bottom")
	)
	(footprint ""
		(layer "F.Cu")
		(at 13.87348 -15.320518 90)
		(property "Reference" "R3178"
			(at 0 0 90)
			(layer "F.SilkS")
			(hide yes)
			(effects
				(font
					(size 1.27 1.27)
				)
			)
		)
		(property "Value" ""
			(at 0 0 90)
			(layer "F.Fab")
			(effects
				(font
					(size 1.27 1.27)
				)
			)
		)
		(duplicate_pad_numbers_are_jumpers no)
		(fp_line
			(start 0.7874 -0.4064)
			(end 0.7874 0.4064)
			(stroke
				(width 0.1524)
				(type default)
			)
			(layer "F.SilkS")
		)
		(fp_line
			(start -0.7874 -0.4064)
			(end 0.7874 -0.4064)
			(stroke
				(width 0.1524)
				(type default)
			)
			(layer "F.SilkS")
		)
		(fp_line
			(start 0.7874 0.4064)
			(end -0.7874 0.4064)
			(stroke
				(width 0.1524)
				(type default)
			)
			(layer "F.SilkS")
		)
		(fp_line
			(start -0.7874 0.4064)
			(end -0.7874 -0.4064)
			(stroke
				(width 0.1524)
				(type default)
			)
			(layer "F.SilkS")
		)
		(fp_line
			(start -0.12065 -0.305054)
			(end -0.12065 -0.2794)
			(stroke
				(width 0.1)
				(type default)
			)
			(layer "F.Fab")
		)
		(fp_line
			(start -0.67945 -0.305054)
			(end -0.12065 -0.305054)
			(stroke
				(width 0.1)
				(type default)
			)
			(layer "F.Fab")
		)
		(fp_line
			(start 0.67945 -0.3048)
			(end 0.67945 0.3048)
			(stroke
				(width 0.1)
				(type default)
			)
			(layer "F.Fab")
		)
		(fp_line
			(start 0.12065 -0.3048)
			(end 0.67945 -0.3048)
			(stroke
				(width 0.1)
				(type default)
			)
			(layer "F.Fab")
		)
		(fp_line
			(start 0.12065 -0.2794)
			(end 0.12065 -0.3048)
			(stroke
				(width 0.1)
				(type default)
			)
			(layer "F.Fab")
		)
		(fp_line
			(start -0.12065 -0.2794)
			(end 0.12065 -0.2794)
			(stroke
				(width 0.1)
				(type default)
			)
			(layer "F.Fab")
		)
		(fp_line
			(start 0.120396 0.2794)
			(end -0.12065 0.2794)
			(stroke
				(width 0.1)
				(type default)
			)
			(layer "F.Fab")
		)
		(fp_line
			(start -0.12065 0.2794)
			(end -0.12065 0.3048)
			(stroke
				(width 0.1)
				(type default)
			)
			(layer "F.Fab")
		)
		(fp_line
			(start 0.67945 0.3048)
			(end 0.120396 0.3048)
			(stroke
				(width 0.1)
				(type default)
			)
			(layer "F.Fab")
		)
		(fp_line
			(start 0.120396 0.3048)
			(end 0.120396 0.2794)
			(stroke
				(width 0.1)
				(type default)
			)
			(layer "F.Fab")
		)
		(fp_line
			(start -0.12065 0.3048)
			(end -0.67945 0.3048)
			(stroke
				(width 0.1)
				(type default)
			)
			(layer "F.Fab")
		)
		(fp_line
			(start -0.67945 0.3048)
			(end -0.67945 -0.305054)
			(stroke
				(width 0.1)
				(type default)
			)
			(layer "F.Fab")
		)
		(pad "1" smd circle
			(at -0.40005 0 90)
			(size 0 0)
			(layers "F.Cu" "F.Mask" "F.Paste")
			(net "USB2_5_R1_DP")
		)
		(pad "2" smd circle
			(at 0.40005 0 90)
			(size 0 0)
			(layers "F.Cu" "F.Mask" "F.Paste")
			(net "USB2_5_DP")
		)
	)
	(footprint ""
		(layer "F.Cu")
		(at 287.83788 -408.75966 -90)
		(property "Reference" "C2459"
			(at 0 0 270)
			(layer "F.SilkS")
			(hide yes)
			(effects
				(font
					(size 1.27 1.27)
				)
			)
		)
		(property "Value" ""
			(at 0 0 270)
			(layer "F.Fab")
			(effects
				(font
					(size 1.27 1.27)
				)
			)
		)
		(duplicate_pad_numbers_are_jumpers no)
		(fp_line
			(start -1.2954 0.5842)
			(end -1.2954 -0.5842)
			(stroke
				(width 0.1524)
				(type default)
			)
			(layer "F.SilkS")
		)
		(fp_line
			(start 1.2954 0.5842)
			(end -1.2954 0.5842)
			(stroke
				(width 0.1524)
				(type default)
			)
			(layer "F.SilkS")
		)
		(fp_line
			(start -1.2954 -0.5842)
			(end 1.2954 -0.5842)
			(stroke
				(width 0.1524)
				(type default)
			)
			(layer "F.SilkS")
		)
		(fp_line
			(start 0 -0.5842)
			(end 0 0.5842)
			(stroke
				(width 0.1524)
				(type default)
			)
			(layer "F.SilkS")
		)
		(fp_line
			(start 1.2954 -0.5842)
			(end 1.2954 0.5842)
			(stroke
				(width 0.1524)
				(type default)
			)
			(layer "F.SilkS")
		)
		(fp_line
			(start -0.8636 0.4572)
			(end -0.8636 0.4064)
			(stroke
				(width 0.1)
				(type default)
			)
			(layer "F.Fab")
		)
		(fp_line
			(start 0.8636 0.4572)
			(end -0.8636 0.4572)
			(stroke
				(width 0.1)
				(type default)
			)
			(layer "F.Fab")
		)
		(fp_line
			(start -1.1938 0.4064)
			(end -1.1938 -0.4064)
			(stroke
				(width 0.1)
				(type default)
			)
			(layer "F.Fab")
		)
		(fp_line
			(start -0.8636 0.4064)
			(end -1.1938 0.4064)
			(stroke
				(width 0.1)
				(type default)
			)
			(layer "F.Fab")
		)
		(fp_line
			(start 0.8636 0.4064)
			(end 0.8636 0.4572)
			(stroke
				(width 0.1)
				(type default)
			)
			(layer "F.Fab")
		)
		(fp_line
			(start 1.1938 0.4064)
			(end 0.8636 0.4064)
			(stroke
				(width 0.1)
				(type default)
			)
			(layer "F.Fab")
		)
		(fp_line
			(start -1.1938 -0.4064)
			(end -0.8636 -0.4064)
			(stroke
				(width 0.1)
				(type default)
			)
			(layer "F.Fab")
		)
		(fp_line
			(start -0.8636 -0.4064)
			(end -0.8636 -0.4572)
			(stroke
				(width 0.1)
				(type default)
			)
			(layer "F.Fab")
		)
		(fp_line
			(start 0.8636 -0.4064)
			(end 1.1938 -0.4064)
			(stroke
				(width 0.1)
				(type default)
			)
			(layer "F.Fab")
		)
		(fp_line
			(start 1.1938 -0.4064)
			(end 1.1938 0.4064)
			(stroke
				(width 0.1)
				(type default)
			)
			(layer "F.Fab")
		)
		(fp_line
			(start -0.8636 -0.4572)
			(end 0.8636 -0.4572)
			(stroke
				(width 0.1)
				(type default)
			)
			(layer "F.Fab")
		)
		(fp_line
			(start 0.8636 -0.4572)
			(end 0.8636 -0.4064)
			(stroke
				(width 0.1)
				(type default)
			)
			(layer "F.Fab")
		)
		(pad "1" smd rect
			(at -0.7366 0 180)
			(size 0.7112 0.8128)
			(layers "F.Cu" "F.Mask" "F.Paste")
			(net "P12V_HSC_TEMP_D+")
		)
		(pad "2" smd rect
			(at 0.7366 0 180)
			(size 0.7112 0.8128)
			(layers "F.Cu" "F.Mask" "F.Paste")
			(net "P12V_HSC_TEMP_D-")
		)
	)
)
